(kicad_pcb
	(version 20260206)
	(generator "pcbnew")
	(generator_version "10.0")
	(general
		(thickness 1.6)
		(legacy_teardrops no)
	)
	(paper "A4")
	(title_block
		(title "Wiwynn_Tioga_Pass_MB.brd")
		(comment 1 "Tioga Pass / footprints 1494-1501 of 4770")
	)
	(layers
		(0 "F.Cu" signal "TOP")
		(4 "In1.Cu" signal "L2GND")
		(6 "In2.Cu" signal "L3")
		(8 "In3.Cu" signal "L4GND")
		(10 "In4.Cu" signal "L5")
		(12 "In5.Cu" signal "L6GND")
		(14 "In6.Cu" signal "L7VCC")
		(16 "In7.Cu" signal "L8VCC")
		(18 "In8.Cu" signal "L9GND")
		(20 "In9.Cu" signal "L10")
		(22 "In10.Cu" signal "L11GND")
		(24 "In11.Cu" signal "L12")
		(26 "In12.Cu" signal "L13GND")
		(2 "B.Cu" signal "BOTTOM")
		(9 "F.Adhes" user "F.Adhesive")
		(11 "B.Adhes" user "B.Adhesive")
		(13 "F.Paste" user "Package Geometry/Pastemask Top")
		(15 "B.Paste" user "Package Geometry/Pastemask Bottom")
		(5 "F.SilkS" user "Ref Des/Silkscreen Top")
		(7 "B.SilkS" user "Ref Des/Silkscreen Bottom")
		(1 "F.Mask" user "Board Geometry/Soldermask Top")
		(3 "B.Mask" user "Board Geometry/Soldermask Bottom")
		(17 "Dwgs.User" user "User.Drawings")
		(19 "Cmts.User" user "User.Comments")
		(21 "Eco1.User" user "User.Eco1")
		(23 "Eco2.User" user "User.Eco2")
		(25 "Edge.Cuts" user "Board Geometry/Outline")
		(27 "Margin" user)
		(31 "F.CrtYd" user "Package Geometry/Place Bound Top")
		(29 "B.CrtYd" user "Package Geometry/Place Bound Bottom")
		(35 "F.Fab" user "Ref Des/Assembly Top")
		(33 "B.Fab" user "Ref Des/Assembly Bottom")
	)
	(footprint ""
		(layer "F.Cu")
		(at 14.6812 -99.5934 90)
		(property "Reference" "R1C14"
			(at 0 0 90)
			(layer "F.SilkS")
			(hide yes)
			(effects
				(font
					(size 1.27 1.27)
				)
			)
		)
		(property "Value" ""
			(at 0 0 90)
			(layer "F.Fab")
			(effects
				(font
					(size 1.27 1.27)
				)
			)
		)
		(duplicate_pad_numbers_are_jumpers no)
		(fp_rect
			(start -0.2794 -0.1016)
			(end 0.2794 0.9906)
			(stroke
				(width 0)
				(type default)
			)
			(fill no)
			(layer "F.CrtYd")
		)
		(fp_line
			(start 0.2794 -0.1016)
			(end -0.2794 -0.1016)
			(stroke
				(width 0.1)
				(type default)
			)
			(layer "F.Fab")
		)
		(fp_line
			(start -0.2794 -0.1016)
			(end -0.2794 0.9906)
			(stroke
				(width 0.1)
				(type default)
			)
			(layer "F.Fab")
		)
		(fp_line
			(start 0.2794 0.9906)
			(end 0.2794 -0.1016)
			(stroke
				(width 0.1)
				(type default)
			)
			(layer "F.Fab")
		)
		(fp_line
			(start -0.2794 0.9906)
			(end 0.2794 0.9906)
			(stroke
				(width 0.1)
				(type default)
			)
			(layer "F.Fab")
		)
		(pad "1" smd rect
			(at 0 0 90)
			(size 0.508 0.508)
			(layers "F.Cu" "F.Mask" "F.Paste")
			(net "P3V3_STBY")
		)
		(pad "2" smd rect
			(at 0 0.889 90)
			(size 0.508 0.508)
			(layers "F.Cu" "F.Mask" "F.Paste")
			(net "VR_PVCCIN_CPU1_VDD")
		)
		(zone
			(layer "F.Cu")
			(hatch none 0.5)
			(connect_pads
				(clearance 0)
			)
			(min_thickness 0.25)
			(keepout
				(tracks allowed)
				(vias not_allowed)
				(pads allowed)
				(copperpour not_allowed)
				(footprints allowed)
			)
			(placement
				(enabled no)
				(sheetname "")
			)
			(fill
				(thermal_gap 0.5)
				(thermal_bridge_width 0.5)
				(island_removal_mode 0)
			)
			(polygon
				(pts
					(xy 14.9352 -99.3394) (xy 15.3162 -99.3394) (xy 15.3162 -99.8474) (xy 14.9352 -99.8474)
				)
			)
		)
		(zone
			(layer "F.Cu")
			(hatch none 0.5)
			(connect_pads
				(clearance 0)
			)
			(min_thickness 0.25)
			(keepout
				(tracks not_allowed)
				(vias allowed)
				(pads allowed)
				(copperpour not_allowed)
				(footprints allowed)
			)
			(placement
				(enabled no)
				(sheetname "")
			)
			(fill
				(thermal_gap 0.5)
				(thermal_bridge_width 0.5)
				(island_removal_mode 0)
			)
			(polygon
				(pts
					(xy 14.9352 -99.3394) (xy 15.3162 -99.3394) (xy 15.3162 -99.8474) (xy 14.9352 -99.8474)
				)
			)
		)
	)
	(footprint ""
		(layer "F.Cu")
		(at 276.000464 -12.954 90)
		(property "Reference" "C5G8"
			(at 1.848866 0.752348 90)
			(unlocked yes)
			(layer "F.SilkS")
			(effects
				(font
					(size 1.27 0.9652)
					(thickness 0.1524)
				)
			)
		)
		(property "Value" ""
			(at 0 0 90)
			(layer "F.Fab")
			(effects
				(font
					(size 1.27 1.27)
				)
			)
		)
		(duplicate_pad_numbers_are_jumpers no)
		(fp_rect
			(start -0.500126 1.598422)
			(end 0.500126 -0.201422)
			(stroke
				(width 0)
				(type default)
			)
			(fill no)
			(layer "F.CrtYd")
		)
		(fp_line
			(start 0.500126 -0.201422)
			(end 0.500126 1.598422)
			(stroke
				(width 0.1)
				(type default)
			)
			(layer "F.Fab")
		)
		(fp_line
			(start -0.500126 -0.201422)
			(end 0.500126 -0.201422)
			(stroke
				(width 0.1)
				(type default)
			)
			(layer "F.Fab")
		)
		(fp_line
			(start 0.500126 1.598422)
			(end -0.500126 1.598422)
			(stroke
				(width 0.1)
				(type default)
			)
			(layer "F.Fab")
		)
		(fp_line
			(start -0.500126 1.598422)
			(end -0.500126 -0.201422)
			(stroke
				(width 0.1)
				(type default)
			)
			(layer "F.Fab")
		)
		(pad "1" smd rect
			(at 0 0)
			(size 0.889 0.9906)
			(layers "F.Cu" "F.Mask" "F.Paste")
			(net "PVDDQ_ABC")
		)
		(pad "2" smd rect
			(at 0 1.397)
			(size 0.889 0.9906)
			(layers "F.Cu" "F.Mask" "F.Paste")
			(net "GND")
		)
		(zone
			(layer "F.Cu")
			(hatch none 0.5)
			(connect_pads
				(clearance 0)
			)
			(min_thickness 0.25)
			(keepout
				(tracks not_allowed)
				(vias allowed)
				(pads allowed)
				(copperpour not_allowed)
				(footprints allowed)
			)
			(placement
				(enabled no)
				(sheetname "")
			)
			(fill
				(thermal_gap 0.5)
				(thermal_bridge_width 0.5)
				(island_removal_mode 0)
			)
			(polygon
				(pts
					(xy 276.952964 -12.4587) (xy 276.952964 -13.4493) (xy 276.444964 -13.4493) (xy 276.444964 -12.4587)
				)
			)
		)
		(zone
			(layer "F.Cu")
			(hatch none 0.5)
			(connect_pads
				(clearance 0)
			)
			(min_thickness 0.25)
			(keepout
				(tracks allowed)
				(vias not_allowed)
				(pads allowed)
				(copperpour not_allowed)
				(footprints allowed)
			)
			(placement
				(enabled no)
				(sheetname "")
			)
			(fill
				(thermal_gap 0.5)
				(thermal_bridge_width 0.5)
				(island_removal_mode 0)
			)
			(polygon
				(pts
					(xy 276.952964 -12.4587) (xy 276.952964 -13.4493) (xy 276.444964 -13.4493) (xy 276.444964 -12.4587)
				)
			)
		)
	)
	(footprint ""
		(layer "F.Cu")
		(at 417.7919 -58.801 -90)
		(property "Reference" "R8E16"
			(at 0 0 270)
			(layer "F.SilkS")
			(hide yes)
			(effects
				(font
					(size 1.27 1.27)
				)
			)
		)
		(property "Value" ""
			(at 0 0 270)
			(layer "F.Fab")
			(effects
				(font
					(size 1.27 1.27)
				)
			)
		)
		(duplicate_pad_numbers_are_jumpers no)
		(fp_poly
			(pts
				(xy -0.2794 -0.1016) (xy 0.2794 -0.1016) (xy 0.2794 0.9906) (xy -0.2794 0.9906)
			)
			(stroke
				(width 0)
				(type default)
			)
			(fill no)
			(layer "F.CrtYd")
		)
		(fp_line
			(start -0.2794 0.9906)
			(end 0.2794 0.9906)
			(stroke
				(width 0.1)
				(type default)
			)
			(layer "F.Fab")
		)
		(fp_line
			(start 0.2794 0.9906)
			(end 0.2794 -0.1016)
			(stroke
				(width 0.1)
				(type default)
			)
			(layer "F.Fab")
		)
		(fp_line
			(start -0.2794 -0.1016)
			(end -0.2794 0.9906)
			(stroke
				(width 0.1)
				(type default)
			)
			(layer "F.Fab")
		)
		(fp_line
			(start 0.2794 -0.1016)
			(end -0.2794 -0.1016)
			(stroke
				(width 0.1)
				(type default)
			)
			(layer "F.Fab")
		)
		(pad "1" smd rect
			(at 0 0 270)
			(size 0.508 0.508)
			(layers "F.Cu" "F.Mask" "F.Paste")
			(net "FM_BIOS_TOP_SWAP")
		)
		(pad "2" smd rect
			(at 0 0.889 270)
			(size 0.508 0.508)
			(layers "F.Cu" "F.Mask" "F.Paste")
			(net "GND")
		)
		(zone
			(layer "F.Cu")
			(hatch none 0.5)
			(connect_pads
				(clearance 0)
			)
			(min_thickness 0.25)
			(keepout
				(tracks not_allowed)
				(vias allowed)
				(pads allowed)
				(copperpour not_allowed)
				(footprints allowed)
			)
			(placement
				(enabled no)
				(sheetname "")
			)
			(fill
				(thermal_gap 0.5)
				(thermal_bridge_width 0.5)
				(island_removal_mode 0)
			)
			(polygon
				(pts
					(xy 417.1569 -59.055) (xy 417.1569 -58.547) (xy 417.5379 -58.547) (xy 417.5379 -59.055)
				)
			)
		)
		(zone
			(layer "F.Cu")
			(hatch none 0.5)
			(connect_pads
				(clearance 0)
			)
			(min_thickness 0.25)
			(keepout
				(tracks allowed)
				(vias not_allowed)
				(pads allowed)
				(copperpour not_allowed)
				(footprints allowed)
			)
			(placement
				(enabled no)
				(sheetname "")
			)
			(fill
				(thermal_gap 0.5)
				(thermal_bridge_width 0.5)
				(island_removal_mode 0)
			)
			(polygon
				(pts
					(xy 417.5379 -59.055) (xy 417.5379 -58.547) (xy 417.1569 -58.547) (xy 417.1569 -59.055)
				)
			)
		)
	)
	(footprint ""
		(layer "F.Cu")
		(at 351.339658 -1.261364 90)
		(property "Reference" "CT52"
			(at 0.4318 2.74447 90)
			(unlocked yes)
			(layer "F.SilkS")
			(effects
				(font
					(size 0.7874 0.5842)
					(thickness 0.1524)
				)
				(justify left)
			)
		)
		(property "Value" ""
			(at 0 0 90)
			(layer "F.Fab")
			(effects
				(font
					(size 1.27 1.27)
				)
			)
		)
		(duplicate_pad_numbers_are_jumpers no)
		(fp_poly
			(pts
				(xy 0.3048 -0.1016) (xy 0.3048 0.9906) (xy -0.3048 0.9906) (xy -0.3048 -0.1016)
			)
			(stroke
				(width 0)
				(type default)
			)
			(fill no)
			(layer "F.CrtYd")
		)
		(fp_line
			(start 0.3048 -0.1016)
			(end -0.3048 -0.1016)
			(stroke
				(width 0.1)
				(type default)
			)
			(layer "F.Fab")
		)
		(fp_line
			(start -0.3048 -0.1016)
			(end -0.3048 0.9906)
			(stroke
				(width 0.1)
				(type default)
			)
			(layer "F.Fab")
		)
		(fp_line
			(start 0.3048 0.9906)
			(end 0.3048 -0.1016)
			(stroke
				(width 0.1)
				(type default)
			)
			(layer "F.Fab")
		)
		(fp_line
			(start -0.3048 0.9906)
			(end 0.3048 0.9906)
			(stroke
				(width 0.1)
				(type default)
			)
			(layer "F.Fab")
		)
		(pad "1" smd rect
			(at 0 0 90)
			(size 0.508 0.508)
			(layers "F.Cu" "F.Mask" "F.Paste")
			(net "VR_PVDDQ_ABC_AIREF2")
		)
		(pad "2" smd rect
			(at 0 0.889 90)
			(size 0.508 0.508)
			(layers "F.Cu" "F.Mask" "F.Paste")
			(net "GND")
		)
		(zone
			(layer "F.Cu")
			(hatch none 0.5)
			(connect_pads
				(clearance 0)
			)
			(min_thickness 0.25)
			(keepout
				(tracks allowed)
				(vias not_allowed)
				(pads allowed)
				(copperpour not_allowed)
				(footprints allowed)
			)
			(placement
				(enabled no)
				(sheetname "")
			)
			(fill
				(thermal_gap 0.5)
				(thermal_bridge_width 0.5)
				(island_removal_mode 0)
			)
			(polygon
				(pts
					(xy 351.593658 -1.007364) (xy 351.593658 -1.515364) (xy 351.974658 -1.515364) (xy 351.974658 -1.007364)
				)
			)
		)
		(zone
			(layer "F.Cu")
			(hatch none 0.5)
			(connect_pads
				(clearance 0)
			)
			(min_thickness 0.25)
			(keepout
				(tracks not_allowed)
				(vias allowed)
				(pads allowed)
				(copperpour not_allowed)
				(footprints allowed)
			)
			(placement
				(enabled no)
				(sheetname "")
			)
			(fill
				(thermal_gap 0.5)
				(thermal_bridge_width 0.5)
				(island_removal_mode 0)
			)
			(polygon
				(pts
					(xy 351.974658 -1.007364) (xy 351.974658 -1.515364) (xy 351.593658 -1.515364) (xy 351.593658 -1.007364)
				)
			)
		)
	)
	(footprint ""
		(layer "F.Cu")
		(at 214.503 -86.4235)
		(property "Reference" "C4D4"
			(at 0 0 0)
			(layer "F.SilkS")
			(hide yes)
			(effects
				(font
					(size 1.27 1.27)
				)
			)
		)
		(property "Value" ""
			(at 0 0 0)
			(layer "F.Fab")
			(effects
				(font
					(size 1.27 1.27)
				)
			)
		)
		(duplicate_pad_numbers_are_jumpers no)
		(fp_poly
			(pts
				(xy -0.4953 -0.2032) (xy 0.4953 -0.2032) (xy 0.4953 1.6002) (xy -0.4953 1.6002)
			)
			(stroke
				(width 0)
				(type default)
			)
			(fill no)
			(layer "F.CrtYd")
		)
		(fp_line
			(start -0.4953 -0.2032)
			(end 0.4953 -0.2032)
			(stroke
				(width 0.1)
				(type default)
			)
			(layer "F.Fab")
		)
		(fp_line
			(start -0.4953 1.6002)
			(end -0.4953 -0.2032)
			(stroke
				(width 0.1)
				(type default)
			)
			(layer "F.Fab")
		)
		(fp_line
			(start 0.4953 -0.2032)
			(end 0.4953 1.6002)
			(stroke
				(width 0.1)
				(type default)
			)
			(layer "F.Fab")
		)
		(fp_line
			(start 0.4953 1.6002)
			(end -0.4953 1.6002)
			(stroke
				(width 0.1)
				(type default)
			)
			(layer "F.Fab")
		)
		(pad "1" smd rect
			(at 0 0)
			(size 0.762 0.889)
			(layers "F.Cu" "F.Mask" "F.Paste")
			(net "PVCCIN_CPU0")
		)
		(pad "2" smd rect
			(at 0 1.397)
			(size 0.762 0.889)
			(layers "F.Cu" "F.Mask" "F.Paste")
			(net "GND")
		)
		(zone
			(layer "F.Cu")
			(hatch none 0.5)
			(connect_pads
				(clearance 0)
			)
			(min_thickness 0.25)
			(keepout
				(tracks not_allowed)
				(vias allowed)
				(pads allowed)
				(copperpour not_allowed)
				(footprints allowed)
			)
			(placement
				(enabled no)
				(sheetname "")
			)
			(fill
				(thermal_gap 0.5)
				(thermal_bridge_width 0.5)
				(island_removal_mode 0)
			)
			(polygon
				(pts
					(xy 214.122 -85.979) (xy 214.884 -85.979) (xy 214.884 -85.471) (xy 214.122 -85.471)
				)
			)
		)
	)
	(footprint ""
		(layer "F.Cu")
		(at 472.227402 -36.880292)
		(property "Reference" "R9F32"
			(at 0 0 0)
			(layer "F.SilkS")
			(hide yes)
			(effects
				(font
					(size 1.27 1.27)
				)
			)
		)
		(property "Value" ""
			(at 0 0 0)
			(layer "F.Fab")
			(effects
				(font
					(size 1.27 1.27)
				)
			)
		)
		(duplicate_pad_numbers_are_jumpers no)
		(fp_poly
			(pts
				(xy -0.2794 -0.1016) (xy 0.2794 -0.1016) (xy 0.2794 0.9906) (xy -0.2794 0.9906)
			)
			(stroke
				(width 0)
				(type default)
			)
			(fill no)
			(layer "F.CrtYd")
		)
		(fp_line
			(start -0.2794 -0.1016)
			(end -0.2794 0.9906)
			(stroke
				(width 0.1)
				(type default)
			)
			(layer "F.Fab")
		)
		(fp_line
			(start -0.2794 0.9906)
			(end 0.2794 0.9906)
			(stroke
				(width 0.1)
				(type default)
			)
			(layer "F.Fab")
		)
		(fp_line
			(start 0.2794 -0.1016)
			(end -0.2794 -0.1016)
			(stroke
				(width 0.1)
				(type default)
			)
			(layer "F.Fab")
		)
		(fp_line
			(start 0.2794 0.9906)
			(end 0.2794 -0.1016)
			(stroke
				(width 0.1)
				(type default)
			)
			(layer "F.Fab")
		)
		(pad "1" smd rect
			(at 0 0)
			(size 0.508 0.508)
			(layers "F.Cu" "F.Mask" "F.Paste")
			(net "VR_P1V2_BMC_STBY_FB")
		)
		(pad "2" smd rect
			(at 0 0.889)
			(size 0.508 0.508)
			(layers "F.Cu" "F.Mask" "F.Paste")
			(net "GND")
		)
		(zone
			(layer "F.Cu")
			(hatch none 0.5)
			(connect_pads
				(clearance 0)
			)
			(min_thickness 0.25)
			(keepout
				(tracks allowed)
				(vias not_allowed)
				(pads allowed)
				(copperpour not_allowed)
				(footprints allowed)
			)
			(placement
				(enabled no)
				(sheetname "")
			)
			(fill
				(thermal_gap 0.5)
				(thermal_bridge_width 0.5)
				(island_removal_mode 0)
			)
			(polygon
				(pts
					(xy 471.973402 -36.626292) (xy 472.481402 -36.626292) (xy 472.481402 -36.245292) (xy 471.973402 -36.245292)
				)
			)
		)
		(zone
			(layer "F.Cu")
			(hatch none 0.5)
			(connect_pads
				(clearance 0)
			)
			(min_thickness 0.25)
			(keepout
				(tracks not_allowed)
				(vias allowed)
				(pads allowed)
				(copperpour not_allowed)
				(footprints allowed)
			)
			(placement
				(enabled no)
				(sheetname "")
			)
			(fill
				(thermal_gap 0.5)
				(thermal_bridge_width 0.5)
				(island_removal_mode 0)
			)
			(polygon
				(pts
					(xy 471.973402 -36.245292) (xy 472.481402 -36.245292) (xy 472.481402 -36.626292) (xy 471.973402 -36.626292)
				)
			)
		)
	)
	(footprint ""
		(layer "F.Cu")
		(at 337.82 -10.3378 90)
		(property "Reference" "CT50"
			(at -0.8382 -0.67818 90)
			(unlocked yes)
			(layer "F.SilkS")
			(effects
				(font
					(size 0.4064 0.254)
					(thickness 0.1524)
				)
				(justify left)
			)
		)
		(property "Value" ""
			(at 0 0 90)
			(layer "F.Fab")
			(effects
				(font
					(size 1.27 1.27)
				)
			)
		)
		(duplicate_pad_numbers_are_jumpers no)
		(fp_poly
			(pts
				(xy 0.3048 -0.1016) (xy 0.3048 0.9906) (xy -0.3048 0.9906) (xy -0.3048 -0.1016)
			)
			(stroke
				(width 0)
				(type default)
			)
			(fill no)
			(layer "F.CrtYd")
		)
		(fp_line
			(start 0.3048 -0.1016)
			(end -0.3048 -0.1016)
			(stroke
				(width 0.1)
				(type default)
			)
			(layer "F.Fab")
		)
		(fp_line
			(start -0.3048 -0.1016)
			(end -0.3048 0.9906)
			(stroke
				(width 0.1)
				(type default)
			)
			(layer "F.Fab")
		)
		(fp_line
			(start 0.3048 0.9906)
			(end 0.3048 -0.1016)
			(stroke
				(width 0.1)
				(type default)
			)
			(layer "F.Fab")
		)
		(fp_line
			(start -0.3048 0.9906)
			(end 0.3048 0.9906)
			(stroke
				(width 0.1)
				(type default)
			)
			(layer "F.Fab")
		)
		(pad "1" smd rect
			(at 0 0 90)
			(size 0.508 0.508)
			(layers "F.Cu" "F.Mask" "F.Paste")
			(net "VR_PVDDQ_ABC_PH1_SW")
		)
		(pad "2" smd rect
			(at 0 0.889 90)
			(size 0.508 0.508)
			(layers "F.Cu" "F.Mask" "F.Paste")
			(net "VR_PVDDQ_ABC_PH1_SW_RC")
		)
		(zone
			(layer "F.Cu")
			(hatch none 0.5)
			(connect_pads
				(clearance 0)
			)
			(min_thickness 0.25)
			(keepout
				(tracks allowed)
				(vias not_allowed)
				(pads allowed)
				(copperpour not_allowed)
				(footprints allowed)
			)
			(placement
				(enabled no)
				(sheetname "")
			)
			(fill
				(thermal_gap 0.5)
				(thermal_bridge_width 0.5)
				(island_removal_mode 0)
			)
			(polygon
				(pts
					(xy 338.074 -10.0838) (xy 338.074 -10.5918) (xy 338.455 -10.5918) (xy 338.455 -10.0838)
				)
			)
		)
		(zone
			(layer "F.Cu")
			(hatch none 0.5)
			(connect_pads
				(clearance 0)
			)
			(min_thickness 0.25)
			(keepout
				(tracks not_allowed)
				(vias allowed)
				(pads allowed)
				(copperpour not_allowed)
				(footprints allowed)
			)
			(placement
				(enabled no)
				(sheetname "")
			)
			(fill
				(thermal_gap 0.5)
				(thermal_bridge_width 0.5)
				(island_removal_mode 0)
			)
			(polygon
				(pts
					(xy 338.455 -10.0838) (xy 338.455 -10.5918) (xy 338.074 -10.5918) (xy 338.074 -10.0838)
				)
			)
		)
	)
	(footprint ""
		(layer "F.Cu")
		(at 28.6004 -41.4782 180)
		(property "Reference" "C1E21"
			(at 0 0 180)
			(layer "F.SilkS")
			(hide yes)
			(effects
				(font
					(size 1.27 1.27)
				)
			)
		)
		(property "Value" ""
			(at 0 0 180)
			(layer "F.Fab")
			(effects
				(font
					(size 1.27 1.27)
				)
			)
		)
		(duplicate_pad_numbers_are_jumpers no)
		(fp_rect
			(start 0.7239 -0.2159)
			(end -0.7239 1.9939)
			(stroke
				(width 0)
				(type default)
			)
			(fill no)
			(layer "F.CrtYd")
		)
		(fp_line
			(start 0.7239 1.9939)
			(end 0.7239 -0.2159)
			(stroke
				(width 0.1)
				(type default)
			)
			(layer "F.Fab")
		)
		(fp_line
			(start 0.7239 -0.2159)
			(end -0.7239 -0.2159)
			(stroke
				(width 0.1)
				(type default)
			)
			(layer "F.Fab")
		)
		(fp_line
			(start -0.7239 1.9939)
			(end 0.7239 1.9939)
			(stroke
				(width 0.1)
				(type default)
			)
			(layer "F.Fab")
		)
		(fp_line
			(start -0.7239 -0.2159)
			(end -0.7239 1.9939)
			(stroke
				(width 0.1)
				(type default)
			)
			(layer "F.Fab")
		)
		(pad "1" smd rect
			(at 0 0 180)
			(size 1.27 1.016)
			(layers "F.Cu" "F.Mask" "F.Paste")
			(net "P12V_FAN")
		)
		(pad "2" smd rect
			(at 0 1.778 180)
			(size 1.27 1.016)
			(layers "F.Cu" "F.Mask" "F.Paste")
			(net "GND")
		)
		(zone
			(layer "F.Cu")
			(hatch none 0.5)
			(connect_pads
				(clearance 0)
			)
			(min_thickness 0.25)
			(keepout
				(tracks not_allowed)
				(vias allowed)
				(pads allowed)
				(copperpour not_allowed)
				(footprints allowed)
			)
			(placement
				(enabled no)
				(sheetname "")
			)
			(fill
				(thermal_gap 0.5)
				(thermal_bridge_width 0.5)
				(island_removal_mode 0)
			)
			(polygon
				(pts
					(xy 27.9654 -41.9862) (xy 29.2354 -41.9862) (xy 29.2354 -42.7482) (xy 27.9654 -42.7482)
				)
			)
		)
	)
)
